(kicad_pcb
	(version 20241229)
	(generator "pcbnew")
	(generator_version "9.0")
	(general
		(thickness 1.63)
		(legacy_teardrops no)
	)
	(paper "A4")
	(title_block
		(title "CM4 Baseboard")
		(date "2026-01-05")
		(rev "1.1.1")
		(company "Antmicro Ltd")
		(comment 1 "www.antmicro.com")
		(comment 9 "footprints 399-403 of 506")
	)
	(layers
		(0 "F.Cu" signal)
		(4 "In1.Cu" power)
		(6 "In2.Cu" power)
		(8 "In3.Cu" signal)
		(10 "In4.Cu" signal)
		(2 "B.Cu" signal)
		(9 "F.Adhes" user "F.Adhesive")
		(11 "B.Adhes" user "B.Adhesive")
		(13 "F.Paste" user)
		(15 "B.Paste" user)
		(5 "F.SilkS" user "F.Silkscreen")
		(7 "B.SilkS" user "B.Silkscreen")
		(1 "F.Mask" user)
		(3 "B.Mask" user)
		(17 "Dwgs.User" user "User.Drawings")
		(19 "Cmts.User" user "User.Comments")
		(21 "Eco1.User" user "User.Eco1")
		(23 "Eco2.User" user "User.Eco2")
		(25 "Edge.Cuts" user)
		(27 "Margin" user)
		(31 "F.CrtYd" user "F.Courtyard")
		(29 "B.CrtYd" user "B.Courtyard")
		(35 "F.Fab" user)
		(33 "B.Fab" user)
	)
	(footprint "antmicro-footprints:R_0402_1005Metric"
		(layer "B.Cu")
		(at 59.667962 161.8805 180)
		(descr "Resistor SMD 0402")
		(tags "resistor SMD 0402")
		(property "Reference" "R305"
			(at -1.52 0.414 0)
			(layer "B.SilkS")
			(effects
				(font
					(size 0.7 0.7)
					(thickness 0.15)
				)
				(justify left bottom mirror)
			)
		)
		(property "Value" "R_470k_0402"
			(at -1.011843 -1.772047 0)
			(layer "B.Fab")
			(effects
				(font
					(size 0.7 0.7)
					(thickness 0.15)
				)
				(justify left bottom mirror)
			)
		)
		(property "Datasheet" "https://www.bourns.com/docs/product-datasheets/cr.pdf"
			(at 0 0 180)
			(layer "B.Fab")
			(hide yes)
			(effects
				(font
					(size 1.27 1.27)
					(thickness 0.15)
				)
			)
		)
		(property "MPN" "CR0402-FX-4703GLF"
			(at 0 0 180)
			(unlocked yes)
			(layer "B.Fab")
			(hide yes)
			(effects
				(font
					(size 1 1)
					(thickness 0.15)
				)
				(justify mirror)
			)
		)
		(property "Manufacturer" "Bourns"
			(at 0 0 180)
			(unlocked yes)
			(layer "B.Fab")
			(hide yes)
			(effects
				(font
					(size 1 1)
					(thickness 0.15)
				)
				(justify mirror)
			)
		)
		(property "License" "Apache-2.0"
			(at 0 0 180)
			(unlocked yes)
			(layer "B.Fab")
			(hide yes)
			(effects
				(font
					(size 1 1)
					(thickness 0.15)
				)
				(justify mirror)
			)
		)
		(property "Author" "Antmicro"
			(at 0 0 180)
			(unlocked yes)
			(layer "B.Fab")
			(hide yes)
			(effects
				(font
					(size 1 1)
					(thickness 0.15)
				)
				(justify mirror)
			)
		)
		(property "Val" "470k"
			(at 0 0 180)
			(unlocked yes)
			(layer "B.Fab")
			(hide yes)
			(effects
				(font
					(size 1 1)
					(thickness 0.15)
				)
				(justify mirror)
			)
		)
		(property "Tolerance" "1%"
			(at 0 0 180)
			(unlocked yes)
			(layer "B.Fab")
			(hide yes)
			(effects
				(font
					(size 1 1)
					(thickness 0.15)
				)
				(justify mirror)
			)
		)
		(sheetname "/Supply/")
		(sheetfile "supply.kicad_sch")
		(attr smd)
		(fp_rect
			(start -0.925 0.47)
			(end 0.925 -0.47)
			(stroke
				(width 0.05)
				(type default)
			)
			(fill no)
			(layer "B.CrtYd")
		)
		(fp_rect
			(start -0.5 0.25)
			(end 0.5 -0.25)
			(stroke
				(width 0.15)
				(type solid)
			)
			(fill no)
			(layer "B.Fab")
		)
		(fp_text user "Author: Antmicro"
			(at -0.95 -4.169 0)
			(layer "B.Fab")
			(effects
				(font
					(size 0.7 0.7)
					(thickness 0.15)
				)
				(justify left bottom mirror)
			)
		)
		(fp_text user "License: Apache-2.0"
			(at -0.95 -5.169 0)
			(layer "B.Fab")
			(effects
				(font
					(size 0.7 0.7)
					(thickness 0.15)
				)
				(justify left bottom mirror)
			)
		)
		(fp_text user "${REFERENCE}"
			(at -0.95 -3.168 0)
			(layer "B.Fab")
			(effects
				(font
					(size 0.7 0.7)
					(thickness 0.15)
				)
				(justify left bottom mirror)
			)
		)
		(pad "1" smd roundrect
			(at -0.48 0 180)
			(size 0.59 0.64)
			(layers "B.Cu" "B.Mask" "B.Paste")
			(roundrect_rratio 0.25)
			(net 3 "GND")
			(pintype "passive")
		)
		(pad "2" smd roundrect
			(at 0.48 0 180)
			(size 0.59 0.64)
			(layers "B.Cu" "B.Mask" "B.Paste")
			(roundrect_rratio 0.25)
			(net 335 "Net-(Q302-BIAS)")
			(pintype "passive")
		)
	)
	(footprint "antmicro-footprints:R_0402_1005Metric"
		(layer "B.Cu")
		(at 52.516962 165.4145)
		(descr "Resistor SMD 0402")
		(tags "resistor SMD 0402")
		(property "Reference" "R303"
			(at 0.201 1.262 0)
			(layer "B.SilkS")
			(effects
				(font
					(size 0.7 0.7)
					(thickness 0.15)
				)
				(justify right bottom mirror)
			)
		)
		(property "Value" "R_33k_0402"
			(at -1.011843 -1.772047 0)
			(layer "B.Fab")
			(effects
				(font
					(size 0.7 0.7)
					(thickness 0.15)
				)
				(justify right bottom mirror)
			)
		)
		(property "Datasheet" "https://www.bourns.com/docs/product-datasheets/cr.pdf"
			(at 0 0 0)
			(layer "B.Fab")
			(hide yes)
			(effects
				(font
					(size 1.27 1.27)
					(thickness 0.15)
				)
			)
		)
		(property "MPN" "CR0402-FX-3302GLF"
			(at 0 0 0)
			(unlocked yes)
			(layer "B.Fab")
			(hide yes)
			(effects
				(font
					(size 1 1)
					(thickness 0.15)
				)
				(justify mirror)
			)
		)
		(property "Manufacturer" "Bourns"
			(at 0 0 0)
			(unlocked yes)
			(layer "B.Fab")
			(hide yes)
			(effects
				(font
					(size 1 1)
					(thickness 0.15)
				)
				(justify mirror)
			)
		)
		(property "License" "Apache-2.0"
			(at 0 0 0)
			(unlocked yes)
			(layer "B.Fab")
			(hide yes)
			(effects
				(font
					(size 1 1)
					(thickness 0.15)
				)
				(justify mirror)
			)
		)
		(property "Author" "Antmicro"
			(at 0 0 0)
			(unlocked yes)
			(layer "B.Fab")
			(hide yes)
			(effects
				(font
					(size 1 1)
					(thickness 0.15)
				)
				(justify mirror)
			)
		)
		(property "Val" "33k"
			(at 0 0 0)
			(unlocked yes)
			(layer "B.Fab")
			(hide yes)
			(effects
				(font
					(size 1 1)
					(thickness 0.15)
				)
				(justify mirror)
			)
		)
		(property "Tolerance" "1%"
			(at 0 0 0)
			(unlocked yes)
			(layer "B.Fab")
			(hide yes)
			(effects
				(font
					(size 1 1)
					(thickness 0.15)
				)
				(justify mirror)
			)
		)
		(sheetname "/Supply/")
		(sheetfile "supply.kicad_sch")
		(attr smd)
		(fp_rect
			(start -0.925 0.47)
			(end 0.925 -0.47)
			(stroke
				(width 0.05)
				(type default)
			)
			(fill no)
			(layer "B.CrtYd")
		)
		(fp_rect
			(start -0.5 0.25)
			(end 0.5 -0.25)
			(stroke
				(width 0.15)
				(type solid)
			)
			(fill no)
			(layer "B.Fab")
		)
		(fp_text user "License: Apache-2.0"
			(at -0.95 -5.169 180)
			(layer "B.Fab")
			(effects
				(font
					(size 0.7 0.7)
					(thickness 0.15)
				)
				(justify left bottom mirror)
			)
		)
		(fp_text user "Author: Antmicro"
			(at -0.95 -4.169 180)
			(layer "B.Fab")
			(effects
				(font
					(size 0.7 0.7)
					(thickness 0.15)
				)
				(justify left bottom mirror)
			)
		)
		(fp_text user "${REFERENCE}"
			(at -0.95 -3.168 180)
			(layer "B.Fab")
			(effects
				(font
					(size 0.7 0.7)
					(thickness 0.15)
				)
				(justify left bottom mirror)
			)
		)
		(pad "1" smd roundrect
			(at -0.48 0)
			(size 0.59 0.64)
			(layers "B.Cu" "B.Mask" "B.Paste")
			(roundrect_rratio 0.25)
			(net 3 "GND")
			(pintype "passive")
		)
		(pad "2" smd roundrect
			(at 0.48 0)
			(size 0.59 0.64)
			(layers "B.Cu" "B.Mask" "B.Paste")
			(roundrect_rratio 0.25)
			(net 336 "Net-(Q303-REF)")
			(pintype "passive")
		)
	)
	(footprint "antmicro-footprints:R_0402_1005Metric"
		(layer "B.Cu")
		(at 92.067962 129.3415 -90)
		(descr "Resistor SMD 0402")
		(tags "resistor SMD 0402")
		(property "Reference" "R919"
			(at -1.955 -1.42 90)
			(layer "B.SilkS")
			(effects
				(font
					(size 0.7 0.7)
					(thickness 0.15)
				)
				(justify left bottom mirror)
			)
		)
		(property "Value" "R_0R_0402"
			(at -1.011843 -1.772047 90)
			(layer "B.Fab")
			(effects
				(font
					(size 0.7 0.7)
					(thickness 0.15)
				)
				(justify left bottom mirror)
			)
		)
		(property "Datasheet" "https://industrial.panasonic.com/cdbs/www-data/pdf/RDA0000/AOA0000C301.pdf"
			(at 0 0 270)
			(layer "B.Fab")
			(hide yes)
			(effects
				(font
					(size 1.27 1.27)
					(thickness 0.15)
				)
			)
		)
		(property "Manufacturer" "Panasonic"
			(at 0 0 270)
			(unlocked yes)
			(layer "B.Fab")
			(hide yes)
			(effects
				(font
					(size 1 1)
					(thickness 0.15)
				)
				(justify mirror)
			)
		)
		(property "MPN" "ERJ2GE0R00X"
			(at 0 0 270)
			(unlocked yes)
			(layer "B.Fab")
			(hide yes)
			(effects
				(font
					(size 1 1)
					(thickness 0.15)
				)
				(justify mirror)
			)
		)
		(property "Val" "0R"
			(at 0 0 270)
			(unlocked yes)
			(layer "B.Fab")
			(hide yes)
			(effects
				(font
					(size 1 1)
					(thickness 0.15)
				)
				(justify mirror)
			)
		)
		(property "License" "Apache-2.0"
			(at 0 0 270)
			(unlocked yes)
			(layer "B.Fab")
			(hide yes)
			(effects
				(font
					(size 1 1)
					(thickness 0.15)
				)
				(justify mirror)
			)
		)
		(property "Author" "Antmicro"
			(at 0 0 270)
			(unlocked yes)
			(layer "B.Fab")
			(hide yes)
			(effects
				(font
					(size 1 1)
					(thickness 0.15)
				)
				(justify mirror)
			)
		)
		(property "Tolerance" "~"
			(at 0 0 270)
			(unlocked yes)
			(layer "B.Fab")
			(hide yes)
			(effects
				(font
					(size 1 1)
					(thickness 0.15)
				)
				(justify mirror)
			)
		)
		(property "Current" "1A"
			(at 0 0 270)
			(unlocked yes)
			(layer "B.Fab")
			(hide yes)
			(effects
				(font
					(size 1 1)
					(thickness 0.15)
				)
				(justify mirror)
			)
		)
		(sheetname "/USB/")
		(sheetfile "usb.kicad_sch")
		(attr smd)
		(fp_rect
			(start -0.925 0.47)
			(end 0.925 -0.47)
			(stroke
				(width 0.05)
				(type default)
			)
			(fill no)
			(layer "B.CrtYd")
		)
		(fp_rect
			(start -0.5 0.25)
			(end 0.5 -0.25)
			(stroke
				(width 0.15)
				(type solid)
			)
			(fill no)
			(layer "B.Fab")
		)
		(fp_text user "License: Apache-2.0"
			(at -0.95 -5.169 90)
			(layer "B.Fab")
			(effects
				(font
					(size 0.7 0.7)
					(thickness 0.15)
				)
				(justify left bottom mirror)
			)
		)
		(fp_text user "${REFERENCE}"
			(at -0.95 -3.168 90)
			(layer "B.Fab")
			(effects
				(font
					(size 0.7 0.7)
					(thickness 0.15)
				)
				(justify left bottom mirror)
			)
		)
		(fp_text user "Author: Antmicro"
			(at -0.95 -4.169 90)
			(layer "B.Fab")
			(effects
				(font
					(size 0.7 0.7)
					(thickness 0.15)
				)
				(justify left bottom mirror)
			)
		)
		(pad "1" smd roundrect
			(at -0.48 0 270)
			(size 0.59 0.64)
			(layers "B.Cu" "B.Mask" "B.Paste")
			(roundrect_rratio 0.25)
			(net 113 "/USB/OUT_FTDI")
			(pintype "passive")
		)
		(pad "2" smd roundrect
			(at 0.48 0 270)
			(size 0.59 0.64)
			(layers "B.Cu" "B.Mask" "B.Paste")
			(roundrect_rratio 0.25)
			(net 27 "/USB/USB_3V3")
			(pintype "passive")
		)
	)
	(footprint "antmicro-footprints:SOT-363"
		(layer "B.Cu")
		(at 45.817962 163.6305)
		(property "Reference" "Q301"
			(at 2.135 1.846 90)
			(layer "B.SilkS")
			(effects
				(font
					(size 0.7 0.7)
					(thickness 0.15)
				)
				(justify right bottom mirror)
			)
		)
		(property "Value" "DZDH0401DW"
			(at 0 -2.2 0)
			(layer "B.Fab")
			(effects
				(font
					(size 0.7 0.7)
					(thickness 0.15)
				)
				(justify right bottom mirror)
			)
		)
		(property "Datasheet" "https://www.mouser.com/datasheet/2/115/DIOD_S_A0011803041_1-2543705.pdf"
			(at 0 0 0)
			(layer "B.Fab")
			(hide yes)
			(effects
				(font
					(size 1.27 1.27)
					(thickness 0.15)
				)
			)
		)
		(property "MPN" "DZDH0401DW"
			(at 0 0 0)
			(unlocked yes)
			(layer "B.Fab")
			(hide yes)
			(effects
				(font
					(size 1 1)
					(thickness 0.15)
				)
				(justify mirror)
			)
		)
		(property "Manufacturer" "Diodes Incorporated"
			(at 0 0 0)
			(unlocked yes)
			(layer "B.Fab")
			(hide yes)
			(effects
				(font
					(size 1 1)
					(thickness 0.15)
				)
				(justify mirror)
			)
		)
		(property "Author" "Antmicro"
			(at 0 0 0)
			(unlocked yes)
			(layer "B.Fab")
			(hide yes)
			(effects
				(font
					(size 1 1)
					(thickness 0.15)
				)
				(justify mirror)
			)
		)
		(property "License" "Apache-2.0"
			(at 0 0 0)
			(unlocked yes)
			(layer "B.Fab")
			(hide yes)
			(effects
				(font
					(size 1 1)
					(thickness 0.15)
				)
				(justify mirror)
			)
		)
		(sheetname "/Supply/")
		(sheetfile "supply.kicad_sch")
		(attr smd)
		(fp_line
			(start -0.8 -1.223)
			(end 0.803 -1.223)
			(stroke
				(width 0.15)
				(type solid)
			)
			(layer "B.SilkS")
		)
		(fp_line
			(start -0.8 -1.146)
			(end -0.8 -1.223)
			(stroke
				(width 0.15)
				(type solid)
			)
			(layer "B.SilkS")
		)
		(fp_line
			(start -0.72 1.153)
			(end -0.72 1.228)
			(stroke
				(width 0.15)
				(type solid)
			)
			(layer "B.SilkS")
		)
		(fp_line
			(start 0.803 -1.146)
			(end 0.803 -1.223)
			(stroke
				(width 0.15)
				(type solid)
			)
			(layer "B.SilkS")
		)
		(fp_line
			(start 0.803 1.153)
			(end 0.803 1.228)
			(stroke
				(width 0.15)
				(type solid)
			)
			(layer "B.SilkS")
		)
		(fp_line
			(start 0.803 1.228)
			(end -0.72 1.228)
			(stroke
				(width 0.15)
				(type solid)
			)
			(layer "B.SilkS")
		)
		(fp_circle
			(center -0.978102 1.2)
			(end -0.928102 1.2)
			(stroke
				(width 0.15)
				(type solid)
			)
			(fill yes)
			(layer "B.SilkS")
		)
		(fp_rect
			(start 1.3 1.3)
			(end -1.3 -1.3)
			(stroke
				(width 0.05)
				(type solid)
			)
			(fill no)
			(layer "B.CrtYd")
		)
		(fp_line
			(start -0.1 1.1)
			(end -0.68 0.52)
			(stroke
				(width 0.15)
				(type solid)
			)
			(layer "B.Fab")
		)
		(fp_rect
			(start 0.68 -1.1)
			(end -0.68 1.1)
			(stroke
				(width 0.15)
				(type solid)
			)
			(fill no)
			(layer "B.Fab")
		)
		(fp_text user "Author: Antmicro"
			(at -1.3 -6.4 180)
			(layer "B.Fab")
			(effects
				(font
					(size 0.7 0.7)
					(thickness 0.15)
				)
				(justify left bottom mirror)
			)
		)
		(fp_text user "License: Apache-2.0"
			(at -1.3 -5.2 180)
			(layer "B.Fab")
			(effects
				(font
					(size 0.7 0.7)
					(thickness 0.15)
				)
				(justify left bottom mirror)
			)
		)
		(fp_text user "${REFERENCE}"
			(at -1.3 -4 180)
			(layer "B.Fab")
			(effects
				(font
					(size 0.7 0.7)
					(thickness 0.15)
				)
				(justify left bottom mirror)
			)
		)
		(pad "1" smd custom
			(at -0.948 0.752 90)
			(size 0.6 0.6)
			(layers "B.Cu" "B.Mask" "B.Paste")
			(net 492 "unconnected-(Q301-NC-Pad1)")
			(pinfunction "NC")
			(pintype "no_connect")
			(options
				(clearance outline)
				(anchor rect)
			)
			(primitives)
		)
		(pad "2" smd rect
			(at -0.948 0.002 90)
			(size 0.4 0.6)
			(layers "B.Cu" "B.Mask" "B.Paste")
			(net 332 "Net-(Q301-REF)")
			(pinfunction "REF")
			(pintype "input")
		)
		(pad "3" smd custom
			(at -0.948 -0.745 90)
			(size 0.6 0.6)
			(layers "B.Cu" "B.Mask" "B.Paste")
			(net 333 "Net-(Q301-BIAS)")
			(pinfunction "BIAS")
			(pintype "output")
			(options
				(clearance outline)
				(anchor rect)
			)
			(primitives)
		)
		(pad "4" smd custom
			(at 0.951 -0.745 90)
			(size 0.6 0.6)
			(layers "B.Cu" "B.Mask" "B.Paste")
			(net 21 "/Supply/VCC_IN")
			(pinfunction "S")
			(pintype "power_in")
			(options
				(clearance outline)
				(anchor rect)
			)
			(primitives)
		)
		(pad "5" smd rect
			(at 0.951 0.002 90)
			(size 0.4 0.6)
			(layers "B.Cu" "B.Mask" "B.Paste")
			(net 493 "unconnected-(Q301-NC-Pad5)")
			(pinfunction "NC")
			(pintype "no_connect")
		)
		(pad "6" smd custom
			(at 0.951 0.752 90)
			(size 0.6 0.6)
			(layers "B.Cu" "B.Mask" "B.Paste")
			(net 472 "Net-(D301-C)")
			(pinfunction "D")
			(pintype "power_in")
			(options
				(clearance outline)
				(anchor rect)
			)
			(primitives)
		)
	)
	(footprint "antmicro-footprints:C_0402_1005Metric"
		(layer "B.Cu")
		(at 99.442962 174.7915 90)
		(descr "Capacitor SMD 0402")
		(tags "capacitor SMD 0402")
		(property "Reference" "C703"
			(at -0.915 6.505 90)
			(layer "B.SilkS")
			(effects
				(font
					(size 0.7 0.7)
					(thickness 0.15)
				)
				(justify right bottom mirror)
			)
		)
		(property "Value" "C_10u_0402"
			(at -1.022927 -2.155213 90)
			(layer "B.Fab")
			(effects
				(font
					(size 0.7 0.7)
					(thickness 0.15)
				)
				(justify right bottom mirror)
			)
		)
		(property "Datasheet" "https://www.yageo.com/en/Chart/Download/pdf/CC0402MRX5R5BB106"
			(at 0 0 90)
			(layer "B.Fab")
			(hide yes)
			(effects
				(font
					(size 1.27 1.27)
					(thickness 0.15)
				)
			)
		)
		(property "MPN" "CC0402MRX5R5BB106"
			(at 0 0 90)
			(unlocked yes)
			(layer "B.Fab")
			(hide yes)
			(effects
				(font
					(size 1 1)
					(thickness 0.15)
				)
				(justify mirror)
			)
		)
		(property "Manufacturer" "YAGEO"
			(at 0 0 90)
			(unlocked yes)
			(layer "B.Fab")
			(hide yes)
			(effects
				(font
					(size 1 1)
					(thickness 0.15)
				)
				(justify mirror)
			)
		)
		(property "License" "Apache-2.0"
			(at 0 0 90)
			(unlocked yes)
			(layer "B.Fab")
			(hide yes)
			(effects
				(font
					(size 1 1)
					(thickness 0.15)
				)
				(justify mirror)
			)
		)
		(property "Author" "Antmicro"
			(at 0 0 90)
			(unlocked yes)
			(layer "B.Fab")
			(hide yes)
			(effects
				(font
					(size 1 1)
					(thickness 0.15)
				)
				(justify mirror)
			)
		)
		(property "Val" "10u"
			(at 0 0 90)
			(unlocked yes)
			(layer "B.Fab")
			(hide yes)
			(effects
				(font
					(size 1 1)
					(thickness 0.15)
				)
				(justify mirror)
			)
		)
		(property "Voltage" ""
			(at 0 0 90)
			(unlocked yes)
			(layer "B.Fab")
			(hide yes)
			(effects
				(font
					(size 1 1)
					(thickness 0.15)
				)
				(justify mirror)
			)
		)
		(property "Dielectric" ""
			(at 0 0 90)
			(unlocked yes)
			(layer "B.Fab")
			(hide yes)
			(effects
				(font
					(size 1 1)
					(thickness 0.15)
				)
				(justify mirror)
			)
		)
		(sheetname "/Display/")
		(sheetfile "display.kicad_sch")
		(attr smd)
		(fp_rect
			(start -0.925 0.47)
			(end 0.925 -0.47)
			(stroke
				(width 0.05)
				(type default)
			)
			(fill no)
			(layer "B.CrtYd")
		)
		(fp_line
			(start 0.504 -0.248)
			(end -0.494 -0.248)
			(stroke
				(width 0.15)
				(type solid)
			)
			(layer "B.Fab")
		)
		(fp_line
			(start -0.494 -0.248)
			(end -0.494 0.25)
			(stroke
				(width 0.15)
				(type solid)
			)
			(layer "B.Fab")
		)
		(fp_line
			(start 0.504 0.25)
			(end 0.504 -0.248)
			(stroke
				(width 0.15)
				(type solid)
			)
			(layer "B.Fab")
		)
		(fp_line
			(start -0.494 0.25)
			(end 0.504 0.25)
			(stroke
				(width 0.15)
				(type solid)
			)
			(layer "B.Fab")
		)
		(fp_text user "Author: Antmicro"
			(at -0.939 -3.399 270)
			(layer "B.Fab")
			(effects
				(font
					(size 0.7 0.7)
					(thickness 0.15)
				)
				(justify left bottom mirror)
			)
		)
		(fp_text user "License: Apache-2.0"
			(at -0.939 -5.799 270)
			(layer "B.Fab")
			(effects
				(font
					(size 0.7 0.7)
					(thickness 0.15)
				)
				(justify left bottom mirror)
			)
		)
		(fp_text user "${REFERENCE}"
			(at -0.939 -4.599 270)
			(layer "B.Fab")
			(effects
				(font
					(size 0.7 0.7)
					(thickness 0.15)
				)
				(justify left bottom mirror)
			)
		)
		(pad "1" smd roundrect
			(at -0.48 0 90)
			(size 0.59 0.64)
			(layers "B.Cu" "B.Mask" "B.Paste")
			(roundrect_rratio 0.25)
			(net 3 "GND")
			(pintype "passive")
		)
		(pad "2" smd roundrect
			(at 0.48 0 90)
			(size 0.59 0.64)
			(layers "B.Cu" "B.Mask" "B.Paste")
			(roundrect_rratio 0.25)
			(net 9 "+3V3")
			(pintype "passive")
		)
	)
)
